# S9S_MB_2U (Grand Teton) — schematic netlist excerpt (pin names and nets, part order shuffled) for the footprints in the layout excerpt that follows; sources: Cadence DE-HDL packaged netlist, KiCad conversion of 03242023_DA0F0TMBIJ0_F0T_Motherboard_J_brd_V01_OCP.brd

R919  Q_RES  10K 1% CHIP  pkg 0402LF  page 221 : A = P3V3_AUX ; B = JTAG_PLD_JTAGEN
PC1920  Q_CAPP  330UF 2.5V +10/-35% EMPTY  pkg SMLF  page 267 : A = PVCCIN_CPU0 ; B = GND

(kicad_pcb
	(version 20260206)
	(generator "pcbnew")
	(generator_version "10.0")
	(general
		(thickness 1.6)
		(legacy_teardrops no)
	)
	(paper "A4")
	(title_block
		(title "03242023_DA0F0TMBIJ0_F0T_Motherboard_J_brd_V01_OCP.brd")
		(comment 1 "Grand Teton / footprints 4737-4738 of 6105")
	)
	(layers
		(0 "F.Cu" signal "TOP")
		(4 "In1.Cu" signal "GND")
		(6 "In2.Cu" signal "IN1")
		(8 "In3.Cu" signal "GND1")
		(10 "In4.Cu" signal "IN2")
		(12 "In5.Cu" signal "GND2")
		(14 "In6.Cu" signal "IN3")
		(16 "In7.Cu" signal "GND3")
		(18 "In8.Cu" signal "VCC")
		(20 "In9.Cu" signal "VCC1")
		(22 "In10.Cu" signal "GND4")
		(24 "In11.Cu" signal "IN4")
		(26 "In12.Cu" signal "GND5")
		(28 "In13.Cu" signal "IN5")
		(30 "In14.Cu" signal "GND6")
		(32 "In15.Cu" signal "IN6")
		(34 "In16.Cu" signal "GND7")
		(2 "B.Cu" signal "BOTTOM")
		(9 "F.Adhes" user "F.Adhesive")
		(11 "B.Adhes" user "B.Adhesive")
		(13 "F.Paste" user "Package Geometry/Pastemask Top")
		(15 "B.Paste" user "Package Geometry/Pastemask Bottom")
		(5 "F.SilkS" user "Ref Des/Silkscreen Top")
		(7 "B.SilkS" user "Ref Des/Silkscreen Bottom")
		(1 "F.Mask" user "Board Geometry/Soldermask Top")
		(3 "B.Mask" user "Board Geometry/Soldermask Bottom")
		(17 "Dwgs.User" user "User.Drawings")
		(19 "Cmts.User" user "User.Comments")
		(21 "Eco1.User" user "User.Eco1")
		(23 "Eco2.User" user "User.Eco2")
		(25 "Edge.Cuts" user "Board Geometry/Outline")
		(27 "Margin" user)
		(31 "F.CrtYd" user "Package Geometry/Place Bound Top")
		(29 "B.CrtYd" user "Package Geometry/Place Bound Bottom")
		(35 "F.Fab" user "Ref Des/Assembly Top")
		(33 "B.Fab" user "Ref Des/Assembly Bottom")
	)
	(footprint ""
		(layer "B.Cu")
		(at 164.64788 -117.566948 180)
		(property "Reference" "R919"
			(at 0 0 0)
			(layer "B.SilkS")
			(hide yes)
			(effects
				(font
					(size 1.27 1.27)
				)
				(justify mirror)
			)
		)
		(property "Value" ""
			(at 0 0 0)
			(layer "B.Fab")
			(effects
				(font
					(size 1.27 1.27)
				)
				(justify mirror)
			)
		)
		(duplicate_pad_numbers_are_jumpers no)
		(fp_line
			(start 0.7874 0.4064)
			(end 0.7874 -0.4064)
			(stroke
				(width 0.1524)
				(type default)
			)
			(layer "B.SilkS")
		)
		(fp_line
			(start 0.7874 -0.4064)
			(end -0.7874 -0.4064)
			(stroke
				(width 0.1524)
				(type default)
			)
			(layer "B.SilkS")
		)
		(fp_line
			(start -0.7874 0.4064)
			(end 0.7874 0.4064)
			(stroke
				(width 0.1524)
				(type default)
			)
			(layer "B.SilkS")
		)
		(fp_line
			(start -0.7874 -0.4064)
			(end -0.7874 0.4064)
			(stroke
				(width 0.1524)
				(type default)
			)
			(layer "B.SilkS")
		)
		(fp_line
			(start 0.67945 0.3048)
			(end 0.67945 -0.305054)
			(stroke
				(width 0.1)
				(type default)
			)
			(layer "B.Fab")
		)
		(fp_line
			(start 0.67945 -0.305054)
			(end 0.12065 -0.305054)
			(stroke
				(width 0.1)
				(type default)
			)
			(layer "B.Fab")
		)
		(fp_line
			(start 0.12065 0.3048)
			(end 0.67945 0.3048)
			(stroke
				(width 0.1)
				(type default)
			)
			(layer "B.Fab")
		)
		(fp_line
			(start 0.12065 0.2794)
			(end 0.12065 0.3048)
			(stroke
				(width 0.1)
				(type default)
			)
			(layer "B.Fab")
		)
		(fp_line
			(start 0.12065 -0.2794)
			(end -0.12065 -0.2794)
			(stroke
				(width 0.1)
				(type default)
			)
			(layer "B.Fab")
		)
		(fp_line
			(start 0.12065 -0.305054)
			(end 0.12065 -0.2794)
			(stroke
				(width 0.1)
				(type default)
			)
			(layer "B.Fab")
		)
		(fp_line
			(start -0.120396 0.3048)
			(end -0.120396 0.2794)
			(stroke
				(width 0.1)
				(type default)
			)
			(layer "B.Fab")
		)
		(fp_line
			(start -0.120396 0.2794)
			(end 0.12065 0.2794)
			(stroke
				(width 0.1)
				(type default)
			)
			(layer "B.Fab")
		)
		(fp_line
			(start -0.12065 -0.2794)
			(end -0.12065 -0.3048)
			(stroke
				(width 0.1)
				(type default)
			)
			(layer "B.Fab")
		)
		(fp_line
			(start -0.12065 -0.3048)
			(end -0.67945 -0.3048)
			(stroke
				(width 0.1)
				(type default)
			)
			(layer "B.Fab")
		)
		(fp_line
			(start -0.67945 0.3048)
			(end -0.120396 0.3048)
			(stroke
				(width 0.1)
				(type default)
			)
			(layer "B.Fab")
		)
		(fp_line
			(start -0.67945 -0.3048)
			(end -0.67945 0.3048)
			(stroke
				(width 0.1)
				(type default)
			)
			(layer "B.Fab")
		)
		(pad "1" smd circle
			(at 0.40005 0)
			(size 0 0)
			(layers "B.Cu" "B.Mask" "B.Paste")
			(net "P3V3_AUX")
		)
		(pad "2" smd circle
			(at -0.40005 0)
			(size 0 0)
			(layers "B.Cu" "B.Mask" "B.Paste")
			(net "JTAG_PLD_JTAGEN")
		)
	)
	(footprint ""
		(layer "B.Cu")
		(at 361.617768 -326.87006 -90)
		(property "Reference" "PC1920"
			(at 0 0 90)
			(layer "B.SilkS")
			(hide yes)
			(effects
				(font
					(size 1.27 1.27)
				)
				(justify mirror)
			)
		)
		(property "Value" ""
			(at 0 0 90)
			(layer "B.Fab")
			(effects
				(font
					(size 1.27 1.27)
				)
				(justify mirror)
			)
		)
		(duplicate_pad_numbers_are_jumpers no)
		(fp_line
			(start -4.533392 2.249932)
			(end 4.533392 2.249932)
			(stroke
				(width 0.1524)
				(type default)
			)
			(layer "B.SilkS")
		)
		(fp_line
			(start 4.533392 2.249932)
			(end 4.533392 -2.249932)
			(stroke
				(width 0.1524)
				(type default)
			)
			(layer "B.SilkS")
		)
		(fp_line
			(start -4.533392 -2.249932)
			(end -4.533392 2.249932)
			(stroke
				(width 0.1524)
				(type default)
			)
			(layer "B.SilkS")
		)
		(fp_line
			(start 4.533392 -2.249932)
			(end -4.533392 -2.249932)
			(stroke
				(width 0.1524)
				(type default)
			)
			(layer "B.SilkS")
		)
		(fp_rect
			(start 5.39242 2.326132)
			(end 4.533392 -2.326132)
			(stroke
				(width 0)
				(type default)
			)
			(fill yes)
			(layer "B.SilkS")
		)
		(fp_line
			(start -3.750056 2.249932)
			(end 3.750056 2.249932)
			(stroke
				(width 0.1)
				(type default)
			)
			(layer "B.Fab")
		)
		(fp_line
			(start 3.750056 2.249932)
			(end 3.750056 -2.249932)
			(stroke
				(width 0.1)
				(type default)
			)
			(layer "B.Fab")
		)
		(fp_line
			(start -3.750056 -2.249932)
			(end -3.750056 2.249932)
			(stroke
				(width 0.1)
				(type default)
			)
			(layer "B.Fab")
		)
		(fp_line
			(start 3.750056 -2.249932)
			(end -3.750056 -2.249932)
			(stroke
				(width 0.1)
				(type default)
			)
			(layer "B.Fab")
		)
		(fp_text user "-"
			(at -4.615688 1.650238 270)
			(unlocked yes)
			(layer "B.SilkS")
			(effects
				(font
					(size 1.905 1.4224)
					(thickness 0.1524)
				)
				(justify left mirror)
			)
		)
		(fp_text user "+"
			(at 6.322314 0.786384 180)
			(unlocked yes)
			(layer "B.SilkS")
			(effects
				(font
					(size 1.905 1.4224)
					(thickness 0.1524)
				)
				(justify left mirror)
			)
		)
		(fp_text user "+"
			(at 6.322314 0.786384 180)
			(unlocked yes)
			(layer "B.Fab")
			(effects
				(font
					(size 1.905 1.4224)
					(thickness 0.1524)
				)
				(justify left mirror)
			)
		)
		(fp_text user "-"
			(at -4.8514 -0.14605 270)
			(unlocked yes)
			(layer "B.Fab")
			(effects
				(font
					(size 1.905 1.4224)
					(thickness 0.1524)
				)
				(justify left mirror)
			)
		)
		(pad "1" smd rect
			(at 3.199892 0 90)
			(size 2.413 2.8194)
			(layers "B.Cu" "B.Mask" "B.Paste")
			(net "PVCCIN_CPU0")
		)
		(pad "2" smd rect
			(at -3.199892 0 90)
			(size 2.413 2.8194)
			(layers "B.Cu" "B.Mask" "B.Paste")
			(net "GND")
		)
	)
)
